(kicad_pcb
	(version 20260206)
	(generator "pcbnew")
	(generator_version "10.0")
	(general
		(thickness 1.6)
		(legacy_teardrops no)
	)
	(paper "A4")
	(title_block
		(title "04192023_DAF0TMB3IC0_F0TG_MB_C_brd_V02_OCP.brd")
		(comment 1 "Grand Teton / footprints 6109-6115 of 8354")
	)
	(layers
		(0 "F.Cu" signal "TOP")
		(4 "In1.Cu" signal "GND")
		(6 "In2.Cu" signal "IN1")
		(8 "In3.Cu" signal "GND1")
		(10 "In4.Cu" signal "IN2")
		(12 "In5.Cu" signal "GND2")
		(14 "In6.Cu" signal "IN3")
		(16 "In7.Cu" signal "GND3")
		(18 "In8.Cu" signal "VCC")
		(20 "In9.Cu" signal "VCC1")
		(22 "In10.Cu" signal "GND4")
		(24 "In11.Cu" signal "IN4")
		(26 "In12.Cu" signal "GND5")
		(28 "In13.Cu" signal "IN5")
		(30 "In14.Cu" signal "GND6")
		(32 "In15.Cu" signal "IN6")
		(34 "In16.Cu" signal "GND7")
		(2 "B.Cu" signal "BOTTOM")
		(9 "F.Adhes" user "F.Adhesive")
		(11 "B.Adhes" user "B.Adhesive")
		(13 "F.Paste" user "Package Geometry/Pastemask Top")
		(15 "B.Paste" user "Package Geometry/Pastemask Bottom")
		(5 "F.SilkS" user "Ref Des/Silkscreen Top")
		(7 "B.SilkS" user "Ref Des/Silkscreen Bottom")
		(1 "F.Mask" user "Board Geometry/Soldermask Top")
		(3 "B.Mask" user "Board Geometry/Soldermask Bottom")
		(17 "Dwgs.User" user "User.Drawings")
		(19 "Cmts.User" user "User.Comments")
		(21 "Eco1.User" user "User.Eco1")
		(23 "Eco2.User" user "User.Eco2")
		(25 "Edge.Cuts" user "Board Geometry/Outline")
		(27 "Margin" user)
		(31 "F.CrtYd" user "Package Geometry/Place Bound Top")
		(29 "B.CrtYd" user "Package Geometry/Place Bound Bottom")
		(35 "F.Fab" user "Ref Des/Assembly Top")
		(33 "B.Fab" user "Ref Des/Assembly Bottom")
	)
	(footprint ""
		(layer "B.Cu")
		(at 152.9969 -13.762228 90)
		(property "Reference" "R2416"
			(at 0 0 90)
			(layer "B.SilkS")
			(hide yes)
			(effects
				(font
					(size 1.27 1.27)
				)
				(justify mirror)
			)
		)
		(property "Value" ""
			(at 0 0 90)
			(layer "B.Fab")
			(effects
				(font
					(size 1.27 1.27)
				)
				(justify mirror)
			)
		)
		(duplicate_pad_numbers_are_jumpers no)
		(fp_line
			(start 0.7874 -0.4064)
			(end -0.7874 -0.4064)
			(stroke
				(width 0.1524)
				(type default)
			)
			(layer "B.SilkS")
		)
		(fp_line
			(start -0.7874 -0.4064)
			(end -0.7874 0.4064)
			(stroke
				(width 0.1524)
				(type default)
			)
			(layer "B.SilkS")
		)
		(fp_line
			(start 0.7874 0.4064)
			(end 0.7874 -0.4064)
			(stroke
				(width 0.1524)
				(type default)
			)
			(layer "B.SilkS")
		)
		(fp_line
			(start -0.7874 0.4064)
			(end 0.7874 0.4064)
			(stroke
				(width 0.1524)
				(type default)
			)
			(layer "B.SilkS")
		)
		(fp_line
			(start 0.67945 -0.305054)
			(end 0.12065 -0.305054)
			(stroke
				(width 0.1)
				(type default)
			)
			(layer "B.Fab")
		)
		(fp_line
			(start 0.12065 -0.305054)
			(end 0.12065 -0.2794)
			(stroke
				(width 0.1)
				(type default)
			)
			(layer "B.Fab")
		)
		(fp_line
			(start -0.12065 -0.3048)
			(end -0.67945 -0.3048)
			(stroke
				(width 0.1)
				(type default)
			)
			(layer "B.Fab")
		)
		(fp_line
			(start -0.67945 -0.3048)
			(end -0.67945 0.3048)
			(stroke
				(width 0.1)
				(type default)
			)
			(layer "B.Fab")
		)
		(fp_line
			(start 0.12065 -0.2794)
			(end -0.12065 -0.2794)
			(stroke
				(width 0.1)
				(type default)
			)
			(layer "B.Fab")
		)
		(fp_line
			(start -0.12065 -0.2794)
			(end -0.12065 -0.3048)
			(stroke
				(width 0.1)
				(type default)
			)
			(layer "B.Fab")
		)
		(fp_line
			(start 0.12065 0.2794)
			(end 0.12065 0.3048)
			(stroke
				(width 0.1)
				(type default)
			)
			(layer "B.Fab")
		)
		(fp_line
			(start -0.120396 0.2794)
			(end 0.12065 0.2794)
			(stroke
				(width 0.1)
				(type default)
			)
			(layer "B.Fab")
		)
		(fp_line
			(start 0.67945 0.3048)
			(end 0.67945 -0.305054)
			(stroke
				(width 0.1)
				(type default)
			)
			(layer "B.Fab")
		)
		(fp_line
			(start 0.12065 0.3048)
			(end 0.67945 0.3048)
			(stroke
				(width 0.1)
				(type default)
			)
			(layer "B.Fab")
		)
		(fp_line
			(start -0.120396 0.3048)
			(end -0.120396 0.2794)
			(stroke
				(width 0.1)
				(type default)
			)
			(layer "B.Fab")
		)
		(fp_line
			(start -0.67945 0.3048)
			(end -0.120396 0.3048)
			(stroke
				(width 0.1)
				(type default)
			)
			(layer "B.Fab")
		)
		(pad "1" smd circle
			(at 0.40005 0 270)
			(size 0 0)
			(layers "B.Cu" "B.Mask" "B.Paste")
			(net "SMB_1_BMC_GPU_SDA")
		)
		(pad "2" smd circle
			(at -0.40005 0 270)
			(size 0 0)
			(layers "B.Cu" "B.Mask" "B.Paste")
			(net "SMB_PCIE3_3V3AUX_SDA_R")
		)
	)
	(footprint ""
		(layer "B.Cu")
		(at 437.66994 -362.77042 -90)
		(property "Reference" "PC7002"
			(at 0 0 90)
			(layer "B.SilkS")
			(hide yes)
			(effects
				(font
					(size 1.27 1.27)
				)
				(justify mirror)
			)
		)
		(property "Value" ""
			(at 0 0 90)
			(layer "B.Fab")
			(effects
				(font
					(size 1.27 1.27)
				)
				(justify mirror)
			)
		)
		(duplicate_pad_numbers_are_jumpers no)
		(fp_line
			(start -1.524 0.762)
			(end 1.524 0.762)
			(stroke
				(width 0.1524)
				(type default)
			)
			(layer "B.SilkS")
		)
		(fp_line
			(start 1.524 0.762)
			(end 1.524 -0.762)
			(stroke
				(width 0.1524)
				(type default)
			)
			(layer "B.SilkS")
		)
		(fp_line
			(start -1.524 -0.762)
			(end -1.524 0.762)
			(stroke
				(width 0.1524)
				(type default)
			)
			(layer "B.SilkS")
		)
		(fp_line
			(start 1.524 -0.762)
			(end -1.524 -0.762)
			(stroke
				(width 0.1524)
				(type default)
			)
			(layer "B.SilkS")
		)
		(fp_line
			(start -1.1049 0.724916)
			(end -1.1049 -0.724916)
			(stroke
				(width 0.1)
				(type default)
			)
			(layer "B.Fab")
		)
		(fp_line
			(start 1.1049 0.724916)
			(end -1.1049 0.724916)
			(stroke
				(width 0.1)
				(type default)
			)
			(layer "B.Fab")
		)
		(fp_line
			(start -1.1049 -0.724916)
			(end 1.1049 -0.724916)
			(stroke
				(width 0.1)
				(type default)
			)
			(layer "B.Fab")
		)
		(fp_line
			(start 1.1049 -0.724916)
			(end 1.1049 0.724916)
			(stroke
				(width 0.1)
				(type default)
			)
			(layer "B.Fab")
		)
		(pad "1" smd rect
			(at 0.889 0 270)
			(size 1.016 1.27)
			(layers "B.Cu" "B.Mask" "B.Paste")
			(net "SW_P12V_AUX_PVDD11_S3_P0_FLT")
		)
		(pad "2" smd rect
			(at -0.889 0 270)
			(size 1.016 1.27)
			(layers "B.Cu" "B.Mask" "B.Paste")
			(net "GND")
		)
	)
	(footprint ""
		(layer "B.Cu")
		(at 257.379724 -132.625084 -90)
		(property "Reference" "C1104"
			(at 0 0 90)
			(layer "B.SilkS")
			(hide yes)
			(effects
				(font
					(size 1.27 1.27)
				)
				(justify mirror)
			)
		)
		(property "Value" ""
			(at 0 0 90)
			(layer "B.Fab")
			(effects
				(font
					(size 1.27 1.27)
				)
				(justify mirror)
			)
		)
		(duplicate_pad_numbers_are_jumpers no)
		(fp_line
			(start -0.7874 0.4064)
			(end 0.7874 0.4064)
			(stroke
				(width 0.1524)
				(type default)
			)
			(layer "B.SilkS")
		)
		(fp_line
			(start 0.7874 0.4064)
			(end 0.7874 -0.4064)
			(stroke
				(width 0.1524)
				(type default)
			)
			(layer "B.SilkS")
		)
		(fp_line
			(start -0.7874 -0.4064)
			(end -0.7874 0.4064)
			(stroke
				(width 0.1524)
				(type default)
			)
			(layer "B.SilkS")
		)
		(fp_line
			(start 0.7874 -0.4064)
			(end -0.7874 -0.4064)
			(stroke
				(width 0.1524)
				(type default)
			)
			(layer "B.SilkS")
		)
		(fp_line
			(start -0.67945 0.3048)
			(end -0.120396 0.3048)
			(stroke
				(width 0.1)
				(type default)
			)
			(layer "B.Fab")
		)
		(fp_line
			(start -0.120396 0.3048)
			(end -0.120396 0.2794)
			(stroke
				(width 0.1)
				(type default)
			)
			(layer "B.Fab")
		)
		(fp_line
			(start 0.12065 0.3048)
			(end 0.67945 0.3048)
			(stroke
				(width 0.1)
				(type default)
			)
			(layer "B.Fab")
		)
		(fp_line
			(start 0.67945 0.3048)
			(end 0.67945 -0.305054)
			(stroke
				(width 0.1)
				(type default)
			)
			(layer "B.Fab")
		)
		(fp_line
			(start -0.120396 0.2794)
			(end 0.12065 0.2794)
			(stroke
				(width 0.1)
				(type default)
			)
			(layer "B.Fab")
		)
		(fp_line
			(start 0.12065 0.2794)
			(end 0.12065 0.3048)
			(stroke
				(width 0.1)
				(type default)
			)
			(layer "B.Fab")
		)
		(fp_line
			(start -0.12065 -0.2794)
			(end -0.12065 -0.3048)
			(stroke
				(width 0.1)
				(type default)
			)
			(layer "B.Fab")
		)
		(fp_line
			(start 0.12065 -0.2794)
			(end -0.12065 -0.2794)
			(stroke
				(width 0.1)
				(type default)
			)
			(layer "B.Fab")
		)
		(fp_line
			(start -0.67945 -0.3048)
			(end -0.67945 0.3048)
			(stroke
				(width 0.1)
				(type default)
			)
			(layer "B.Fab")
		)
		(fp_line
			(start -0.12065 -0.3048)
			(end -0.67945 -0.3048)
			(stroke
				(width 0.1)
				(type default)
			)
			(layer "B.Fab")
		)
		(fp_line
			(start 0.12065 -0.305054)
			(end 0.12065 -0.2794)
			(stroke
				(width 0.1)
				(type default)
			)
			(layer "B.Fab")
		)
		(fp_line
			(start 0.67945 -0.305054)
			(end 0.12065 -0.305054)
			(stroke
				(width 0.1)
				(type default)
			)
			(layer "B.Fab")
		)
		(pad "1" smd circle
			(at 0.40005 0 90)
			(size 0 0)
			(layers "B.Cu" "B.Mask" "B.Paste")
			(net "P3V3_AUX")
		)
		(pad "2" smd circle
			(at -0.40005 0 90)
			(size 0 0)
			(layers "B.Cu" "B.Mask" "B.Paste")
			(net "GND")
		)
	)
	(footprint ""
		(layer "B.Cu")
		(at 393.381484 -204.249782)
		(property "Reference" "R6130"
			(at 0 0 0)
			(layer "B.SilkS")
			(hide yes)
			(effects
				(font
					(size 1.27 1.27)
				)
				(justify mirror)
			)
		)
		(property "Value" ""
			(at 0 0 0)
			(layer "B.Fab")
			(effects
				(font
					(size 1.27 1.27)
				)
				(justify mirror)
			)
		)
		(duplicate_pad_numbers_are_jumpers no)
		(fp_line
			(start -0.7874 -0.4064)
			(end -0.7874 0.4064)
			(stroke
				(width 0.1524)
				(type default)
			)
			(layer "B.SilkS")
		)
		(fp_line
			(start -0.7874 0.4064)
			(end 0.7874 0.4064)
			(stroke
				(width 0.1524)
				(type default)
			)
			(layer "B.SilkS")
		)
		(fp_line
			(start 0.7874 -0.4064)
			(end -0.7874 -0.4064)
			(stroke
				(width 0.1524)
				(type default)
			)
			(layer "B.SilkS")
		)
		(fp_line
			(start 0.7874 0.4064)
			(end 0.7874 -0.4064)
			(stroke
				(width 0.1524)
				(type default)
			)
			(layer "B.SilkS")
		)
		(fp_line
			(start -0.67945 -0.3048)
			(end -0.67945 0.3048)
			(stroke
				(width 0.1)
				(type default)
			)
			(layer "B.Fab")
		)
		(fp_line
			(start -0.67945 0.3048)
			(end -0.120396 0.3048)
			(stroke
				(width 0.1)
				(type default)
			)
			(layer "B.Fab")
		)
		(fp_line
			(start -0.12065 -0.3048)
			(end -0.67945 -0.3048)
			(stroke
				(width 0.1)
				(type default)
			)
			(layer "B.Fab")
		)
		(fp_line
			(start -0.12065 -0.2794)
			(end -0.12065 -0.3048)
			(stroke
				(width 0.1)
				(type default)
			)
			(layer "B.Fab")
		)
		(fp_line
			(start -0.120396 0.2794)
			(end 0.12065 0.2794)
			(stroke
				(width 0.1)
				(type default)
			)
			(layer "B.Fab")
		)
		(fp_line
			(start -0.120396 0.3048)
			(end -0.120396 0.2794)
			(stroke
				(width 0.1)
				(type default)
			)
			(layer "B.Fab")
		)
		(fp_line
			(start 0.12065 -0.305054)
			(end 0.12065 -0.2794)
			(stroke
				(width 0.1)
				(type default)
			)
			(layer "B.Fab")
		)
		(fp_line
			(start 0.12065 -0.2794)
			(end -0.12065 -0.2794)
			(stroke
				(width 0.1)
				(type default)
			)
			(layer "B.Fab")
		)
		(fp_line
			(start 0.12065 0.2794)
			(end 0.12065 0.3048)
			(stroke
				(width 0.1)
				(type default)
			)
			(layer "B.Fab")
		)
		(fp_line
			(start 0.12065 0.3048)
			(end 0.67945 0.3048)
			(stroke
				(width 0.1)
				(type default)
			)
			(layer "B.Fab")
		)
		(fp_line
			(start 0.67945 -0.305054)
			(end 0.12065 -0.305054)
			(stroke
				(width 0.1)
				(type default)
			)
			(layer "B.Fab")
		)
		(fp_line
			(start 0.67945 0.3048)
			(end 0.67945 -0.305054)
			(stroke
				(width 0.1)
				(type default)
			)
			(layer "B.Fab")
		)
		(pad "1" smd circle
			(at 0.40005 0 180)
			(size 0 0)
			(layers "B.Cu" "B.Mask" "B.Paste")
			(net "PVDD18_S5_P0")
		)
		(pad "2" smd circle
			(at -0.40005 0 180)
			(size 0 0)
			(layers "B.Cu" "B.Mask" "B.Paste")
			(net "FAB_REV_ID2")
		)
	)
	(footprint ""
		(layer "B.Cu")
		(at 371.805454 -268.41831)
		(property "Reference" "C2245"
			(at 0 0 0)
			(layer "B.SilkS")
			(hide yes)
			(effects
				(font
					(size 1.27 1.27)
				)
				(justify mirror)
			)
		)
		(property "Value" ""
			(at 0 0 0)
			(layer "B.Fab")
			(effects
				(font
					(size 1.27 1.27)
				)
				(justify mirror)
			)
		)
		(duplicate_pad_numbers_are_jumpers no)
		(fp_line
			(start -0.7874 -0.4064)
			(end -0.7874 0.4064)
			(stroke
				(width 0.1524)
				(type default)
			)
			(layer "B.SilkS")
		)
		(fp_line
			(start -0.7874 0.4064)
			(end 0.7874 0.4064)
			(stroke
				(width 0.1524)
				(type default)
			)
			(layer "B.SilkS")
		)
		(fp_line
			(start 0.7874 -0.4064)
			(end -0.7874 -0.4064)
			(stroke
				(width 0.1524)
				(type default)
			)
			(layer "B.SilkS")
		)
		(fp_line
			(start 0.7874 0.4064)
			(end 0.7874 -0.4064)
			(stroke
				(width 0.1524)
				(type default)
			)
			(layer "B.SilkS")
		)
		(fp_line
			(start -0.67945 -0.3048)
			(end -0.67945 0.3048)
			(stroke
				(width 0.1)
				(type default)
			)
			(layer "B.Fab")
		)
		(fp_line
			(start -0.67945 0.3048)
			(end -0.120396 0.3048)
			(stroke
				(width 0.1)
				(type default)
			)
			(layer "B.Fab")
		)
		(fp_line
			(start -0.12065 -0.3048)
			(end -0.67945 -0.3048)
			(stroke
				(width 0.1)
				(type default)
			)
			(layer "B.Fab")
		)
		(fp_line
			(start -0.12065 -0.2794)
			(end -0.12065 -0.3048)
			(stroke
				(width 0.1)
				(type default)
			)
			(layer "B.Fab")
		)
		(fp_line
			(start -0.120396 0.2794)
			(end 0.12065 0.2794)
			(stroke
				(width 0.1)
				(type default)
			)
			(layer "B.Fab")
		)
		(fp_line
			(start -0.120396 0.3048)
			(end -0.120396 0.2794)
			(stroke
				(width 0.1)
				(type default)
			)
			(layer "B.Fab")
		)
		(fp_line
			(start 0.12065 -0.305054)
			(end 0.12065 -0.2794)
			(stroke
				(width 0.1)
				(type default)
			)
			(layer "B.Fab")
		)
		(fp_line
			(start 0.12065 -0.2794)
			(end -0.12065 -0.2794)
			(stroke
				(width 0.1)
				(type default)
			)
			(layer "B.Fab")
		)
		(fp_line
			(start 0.12065 0.2794)
			(end 0.12065 0.3048)
			(stroke
				(width 0.1)
				(type default)
			)
			(layer "B.Fab")
		)
		(fp_line
			(start 0.12065 0.3048)
			(end 0.67945 0.3048)
			(stroke
				(width 0.1)
				(type default)
			)
			(layer "B.Fab")
		)
		(fp_line
			(start 0.67945 -0.305054)
			(end 0.12065 -0.305054)
			(stroke
				(width 0.1)
				(type default)
			)
			(layer "B.Fab")
		)
		(fp_line
			(start 0.67945 0.3048)
			(end 0.67945 -0.305054)
			(stroke
				(width 0.1)
				(type default)
			)
			(layer "B.Fab")
		)
		(pad "1" smd circle
			(at 0.40005 0 180)
			(size 0 0)
			(layers "B.Cu" "B.Mask" "B.Paste")
			(net "PVDDCR_CPU1_P0")
		)
		(pad "2" smd circle
			(at -0.40005 0 180)
			(size 0 0)
			(layers "B.Cu" "B.Mask" "B.Paste")
			(net "GND")
		)
	)
	(footprint ""
		(layer "B.Cu")
		(at 379.613922 -148.30171 -90)
		(property "Reference" "PR531"
			(at 0 0 90)
			(layer "B.SilkS")
			(hide yes)
			(effects
				(font
					(size 1.27 1.27)
				)
				(justify mirror)
			)
		)
		(property "Value" ""
			(at 0 0 90)
			(layer "B.Fab")
			(effects
				(font
					(size 1.27 1.27)
				)
				(justify mirror)
			)
		)
		(duplicate_pad_numbers_are_jumpers no)
		(fp_line
			(start -0.7874 0.4064)
			(end 0.7874 0.4064)
			(stroke
				(width 0.1524)
				(type default)
			)
			(layer "B.SilkS")
		)
		(fp_line
			(start 0.7874 0.4064)
			(end 0.7874 -0.4064)
			(stroke
				(width 0.1524)
				(type default)
			)
			(layer "B.SilkS")
		)
		(fp_line
			(start -0.7874 -0.4064)
			(end -0.7874 0.4064)
			(stroke
				(width 0.1524)
				(type default)
			)
			(layer "B.SilkS")
		)
		(fp_line
			(start 0.7874 -0.4064)
			(end -0.7874 -0.4064)
			(stroke
				(width 0.1524)
				(type default)
			)
			(layer "B.SilkS")
		)
		(fp_line
			(start -0.67945 0.3048)
			(end -0.120396 0.3048)
			(stroke
				(width 0.1)
				(type default)
			)
			(layer "B.Fab")
		)
		(fp_line
			(start -0.120396 0.3048)
			(end -0.120396 0.2794)
			(stroke
				(width 0.1)
				(type default)
			)
			(layer "B.Fab")
		)
		(fp_line
			(start 0.12065 0.3048)
			(end 0.67945 0.3048)
			(stroke
				(width 0.1)
				(type default)
			)
			(layer "B.Fab")
		)
		(fp_line
			(start 0.67945 0.3048)
			(end 0.67945 -0.305054)
			(stroke
				(width 0.1)
				(type default)
			)
			(layer "B.Fab")
		)
		(fp_line
			(start -0.120396 0.2794)
			(end 0.12065 0.2794)
			(stroke
				(width 0.1)
				(type default)
			)
			(layer "B.Fab")
		)
		(fp_line
			(start 0.12065 0.2794)
			(end 0.12065 0.3048)
			(stroke
				(width 0.1)
				(type default)
			)
			(layer "B.Fab")
		)
		(fp_line
			(start -0.12065 -0.2794)
			(end -0.12065 -0.3048)
			(stroke
				(width 0.1)
				(type default)
			)
			(layer "B.Fab")
		)
		(fp_line
			(start 0.12065 -0.2794)
			(end -0.12065 -0.2794)
			(stroke
				(width 0.1)
				(type default)
			)
			(layer "B.Fab")
		)
		(fp_line
			(start -0.67945 -0.3048)
			(end -0.67945 0.3048)
			(stroke
				(width 0.1)
				(type default)
			)
			(layer "B.Fab")
		)
		(fp_line
			(start -0.12065 -0.3048)
			(end -0.67945 -0.3048)
			(stroke
				(width 0.1)
				(type default)
			)
			(layer "B.Fab")
		)
		(fp_line
			(start 0.12065 -0.305054)
			(end 0.12065 -0.2794)
			(stroke
				(width 0.1)
				(type default)
			)
			(layer "B.Fab")
		)
		(fp_line
			(start 0.67945 -0.305054)
			(end 0.12065 -0.305054)
			(stroke
				(width 0.1)
				(type default)
			)
			(layer "B.Fab")
		)
		(pad "1" smd circle
			(at 0.40005 0 90)
			(size 0 0)
			(layers "B.Cu" "B.Mask" "B.Paste")
			(net "NC_PVDDCR_CPU0_P0_IMON7")
		)
		(pad "2" smd circle
			(at -0.40005 0 90)
			(size 0 0)
			(layers "B.Cu" "B.Mask" "B.Paste")
			(net "GND")
		)
	)
	(footprint ""
		(layer "B.Cu")
		(at 58.656982 -153.821892 180)
		(property "Reference" "PC65"
			(at 0 0 0)
			(layer "B.SilkS")
			(hide yes)
			(effects
				(font
					(size 1.27 1.27)
				)
				(justify mirror)
			)
		)
		(property "Value" ""
			(at 0 0 0)
			(layer "B.Fab")
			(effects
				(font
					(size 1.27 1.27)
				)
				(justify mirror)
			)
		)
		(duplicate_pad_numbers_are_jumpers no)
		(fp_line
			(start 1.524 0.762)
			(end 1.524 -0.762)
			(stroke
				(width 0.1524)
				(type default)
			)
			(layer "B.SilkS")
		)
		(fp_line
			(start 1.524 -0.762)
			(end -1.524 -0.762)
			(stroke
				(width 0.1524)
				(type default)
			)
			(layer "B.SilkS")
		)
		(fp_line
			(start -1.524 0.762)
			(end 1.524 0.762)
			(stroke
				(width 0.1524)
				(type default)
			)
			(layer "B.SilkS")
		)
		(fp_line
			(start -1.524 -0.762)
			(end -1.524 0.762)
			(stroke
				(width 0.1524)
				(type default)
			)
			(layer "B.SilkS")
		)
		(fp_line
			(start 1.1049 0.724916)
			(end -1.1049 0.724916)
			(stroke
				(width 0.1)
				(type default)
			)
			(layer "B.Fab")
		)
		(fp_line
			(start 1.1049 -0.724916)
			(end 1.1049 0.724916)
			(stroke
				(width 0.1)
				(type default)
			)
			(layer "B.Fab")
		)
		(fp_line
			(start -1.1049 0.724916)
			(end -1.1049 -0.724916)
			(stroke
				(width 0.1)
				(type default)
			)
			(layer "B.Fab")
		)
		(fp_line
			(start -1.1049 -0.724916)
			(end 1.1049 -0.724916)
			(stroke
				(width 0.1)
				(type default)
			)
			(layer "B.Fab")
		)
		(pad "1" smd rect
			(at 0.889 0 180)
			(size 1.016 1.27)
			(layers "B.Cu" "B.Mask" "B.Paste")
			(net "PVDD18_S5_P1")
		)
		(pad "2" smd rect
			(at -0.889 0 180)
			(size 1.016 1.27)
			(layers "B.Cu" "B.Mask" "B.Paste")
			(net "GND")
		)
	)
)
